(kicad_pcb
	(version 20241229)
	(generator "pcbnew")
	(generator_version "9.0")
	(general
		(thickness 1.63)
		(legacy_teardrops no)
	)
	(paper "A4")
	(title_block
		(title "CM4 Baseboard")
		(date "2026-01-05")
		(rev "1.1.1")
		(company "Antmicro Ltd")
		(comment 1 "www.antmicro.com")
		(comment 9 "footprints 483-486 of 506")
	)
	(layers
		(0 "F.Cu" signal)
		(4 "In1.Cu" power)
		(6 "In2.Cu" power)
		(8 "In3.Cu" signal)
		(10 "In4.Cu" signal)
		(2 "B.Cu" signal)
		(9 "F.Adhes" user "F.Adhesive")
		(11 "B.Adhes" user "B.Adhesive")
		(13 "F.Paste" user)
		(15 "B.Paste" user)
		(5 "F.SilkS" user "F.Silkscreen")
		(7 "B.SilkS" user "B.Silkscreen")
		(1 "F.Mask" user)
		(3 "B.Mask" user)
		(17 "Dwgs.User" user "User.Drawings")
		(19 "Cmts.User" user "User.Comments")
		(21 "Eco1.User" user "User.Eco1")
		(23 "Eco2.User" user "User.Eco2")
		(25 "Edge.Cuts" user)
		(27 "Margin" user)
		(31 "F.CrtYd" user "F.Courtyard")
		(29 "B.CrtYd" user "B.Courtyard")
		(35 "F.Fab" user)
		(33 "B.Fab" user)
	)
	(footprint "antmicro-footprints:Spacer_Drill3.7mm_H6mm_9774060151R"
		(layer "B.Cu")
		(at 41.917962 116.7165)
		(descr "Spacer M=3 h=36mm fi=5.1mm")
		(property "Reference" "H103"
			(at 1.46 -3.3 180)
			(layer "B.SilkS")
			(effects
				(font
					(size 0.7 0.7)
					(thickness 0.15)
				)
				(justify left bottom mirror)
			)
		)
		(property "Value" "Spacer_Drill3.7mm_H6mm_9774060151R"
			(at 0 -4 180)
			(layer "B.Fab")
			(effects
				(font
					(size 0.7 0.7)
					(thickness 0.15)
				)
				(justify left bottom mirror)
			)
		)
		(property "Datasheet" "https://www.we-online.com/components/products/datasheet/9774060151R.pdf"
			(at 0 0 0)
			(layer "B.Fab")
			(hide yes)
			(effects
				(font
					(size 1.27 1.27)
					(thickness 0.15)
				)
			)
		)
		(property "Manufacturer" "Würth Elektronik"
			(at 0 0 0)
			(unlocked yes)
			(layer "B.Fab")
			(hide yes)
			(effects
				(font
					(size 1 1)
					(thickness 0.15)
				)
				(justify mirror)
			)
		)
		(property "MPN" "9774060151R"
			(at 0 0 0)
			(unlocked yes)
			(layer "B.Fab")
			(hide yes)
			(effects
				(font
					(size 1 1)
					(thickness 0.15)
				)
				(justify mirror)
			)
		)
		(property "Author" "Antmicro"
			(at 0 0 0)
			(unlocked yes)
			(layer "B.Fab")
			(hide yes)
			(effects
				(font
					(size 1 1)
					(thickness 0.15)
				)
				(justify mirror)
			)
		)
		(property "License" "Apache-2.0"
			(at 0 0 0)
			(unlocked yes)
			(layer "B.Fab")
			(hide yes)
			(effects
				(font
					(size 1 1)
					(thickness 0.15)
				)
				(justify mirror)
			)
		)
		(sheetname "/")
		(sheetfile "cm4-baseboard.kicad_sch")
		(solder_paste_margin_ratio -1)
		(attr smd)
		(fp_circle
			(center 0 0)
			(end 3.05 0)
			(stroke
				(width 0.05)
				(type solid)
			)
			(fill no)
			(layer "B.CrtYd")
		)
		(fp_circle
			(center 0 0)
			(end 2.6 0)
			(stroke
				(width 0.15)
				(type solid)
			)
			(fill no)
			(layer "B.Fab")
		)
		(fp_text user "${REFERENCE}"
			(at -9.6 -6.5 180)
			(layer "B.Fab")
			(effects
				(font
					(size 0.7 0.7)
					(thickness 0.15)
				)
				(justify left bottom mirror)
			)
		)
		(fp_text user "License: Apache-2.0"
			(at -9.6 -8.9 180)
			(layer "B.Fab")
			(effects
				(font
					(size 0.7 0.7)
					(thickness 0.15)
				)
				(justify left bottom mirror)
			)
		)
		(fp_text user "Author: Antmicro"
			(at -9.6 -7.7 180)
			(layer "B.Fab")
			(effects
				(font
					(size 0.7 0.7)
					(thickness 0.15)
				)
				(justify left bottom mirror)
			)
		)
		(pad "" smd custom
			(at -1.7 -1.7 270)
			(size 0.62 0.62)
			(layers "B.Paste")
			(thermal_bridge_angle 90)
			(options
				(clearance outline)
				(anchor circle)
			)
			(primitives
				(gr_arc
					(start 1.266786 0.24747)
					(mid 0.285453 -0.29439)
					(end -0.250195 -1.279127)
					(width 0.2)
				)
				(gr_arc
					(start 1.259603 0.339191)
					(mid 0.218448 -0.232561)
					(end -0.34334 -1.279127)
					(width 0.2)
				)
				(gr_arc
					(start 1.255279 0.431435)
					(mid 0.152481 -0.169693)
					(end -0.436309 -1.279127)
					(width 0.2)
				)
				(gr_arc
					(start 1.253811 0.524161)
					(mid 0.087542 -0.105784)
					(end -0.529126 -1.279127)
					(width 0.2)
				)
				(gr_arc
					(start 1.275473 0.621136)
					(mid 0.0309 -0.033527)
					(end -0.621807 -1.279127)
					(width 0.2)
				)
				(gr_arc
					(start 1.263664 0.711602)
					(mid -0.037759 0.026651)
					(end -0.71437 -1.279127)
					(width 0.2)
				)
				(gr_arc
					(start 1.253435 0.802342)
					(mid -0.105837 0.087395)
					(end -0.806826 -1.279127)
					(width 0.2)
				)
				(gr_arc
					(start 1.267475 0.897258)
					(mid -0.165236 0.156885)
					(end -0.899187 -1.279127)
					(width 0.2)
				)
				(gr_arc
					(start 1.270645 0.990112)
					(mid -0.228522 0.222449)
					(end -0.991463 -1.279127)
					(width 0.2)
				)
				(gr_arc
					(start 1.266278 1.081674)
					(mid -0.294507 0.285313)
					(end -1.083663 -1.279127)
					(width 0.2)
				)
				(gr_line
					(start 1.279127 0.250195)
					(end 1.279127 1.083663)
					(width 0.2)
				)
				(gr_line
					(start -0.250195 -1.279127)
					(end -1.083663 -1.279127)
					(width 0.2)
				)
			)
		)
		(pad "" smd custom
			(at -1.7 1.7)
			(size 0.62 0.62)
			(layers "B.Paste")
			(thermal_bridge_angle 90)
			(options
				(clearance outline)
				(anchor circle)
			)
			(primitives
				(gr_arc
					(start 1.266786 0.24747)
					(mid 0.285453 -0.29439)
					(end -0.250195 -1.279127)
					(width 0.2)
				)
				(gr_arc
					(start 1.259603 0.339191)
					(mid 0.218448 -0.232561)
					(end -0.34334 -1.279127)
					(width 0.2)
				)
				(gr_arc
					(start 1.255279 0.431435)
					(mid 0.152481 -0.169693)
					(end -0.436309 -1.279127)
					(width 0.2)
				)
				(gr_arc
					(start 1.253811 0.524161)
					(mid 0.087542 -0.105784)
					(end -0.529126 -1.279127)
					(width 0.2)
				)
				(gr_arc
					(start 1.275473 0.621136)
					(mid 0.0309 -0.033527)
					(end -0.621807 -1.279127)
					(width 0.2)
				)
				(gr_arc
					(start 1.263664 0.711602)
					(mid -0.037759 0.026651)
					(end -0.71437 -1.279127)
					(width 0.2)
				)
				(gr_arc
					(start 1.253435 0.802342)
					(mid -0.105837 0.087395)
					(end -0.806826 -1.279127)
					(width 0.2)
				)
				(gr_arc
					(start 1.267475 0.897258)
					(mid -0.165236 0.156885)
					(end -0.899187 -1.279127)
					(width 0.2)
				)
				(gr_arc
					(start 1.270645 0.990112)
					(mid -0.228522 0.222449)
					(end -0.991463 -1.279127)
					(width 0.2)
				)
				(gr_arc
					(start 1.266278 1.081674)
					(mid -0.294507 0.285313)
					(end -1.083663 -1.279127)
					(width 0.2)
				)
				(gr_line
					(start 1.279127 0.250195)
					(end 1.279127 1.083663)
					(width 0.2)
				)
				(gr_line
					(start -0.250195 -1.279127)
					(end -1.083663 -1.279127)
					(width 0.2)
				)
			)
		)
		(pad "" smd custom
			(at 1.7 -1.7 180)
			(size 0.62 0.62)
			(layers "B.Paste")
			(thermal_bridge_angle 90)
			(options
				(clearance outline)
				(anchor circle)
			)
			(primitives
				(gr_arc
					(start 1.266786 0.24747)
					(mid 0.285453 -0.29439)
					(end -0.250195 -1.279127)
					(width 0.2)
				)
				(gr_arc
					(start 1.259603 0.339191)
					(mid 0.218448 -0.232561)
					(end -0.34334 -1.279127)
					(width 0.2)
				)
				(gr_arc
					(start 1.255279 0.431435)
					(mid 0.152481 -0.169693)
					(end -0.436309 -1.279127)
					(width 0.2)
				)
				(gr_arc
					(start 1.253811 0.524161)
					(mid 0.087542 -0.105784)
					(end -0.529126 -1.279127)
					(width 0.2)
				)
				(gr_arc
					(start 1.275473 0.621136)
					(mid 0.0309 -0.033527)
					(end -0.621807 -1.279127)
					(width 0.2)
				)
				(gr_arc
					(start 1.263664 0.711602)
					(mid -0.037759 0.026651)
					(end -0.71437 -1.279127)
					(width 0.2)
				)
				(gr_arc
					(start 1.253435 0.802342)
					(mid -0.105837 0.087395)
					(end -0.806826 -1.279127)
					(width 0.2)
				)
				(gr_arc
					(start 1.267475 0.897258)
					(mid -0.165236 0.156885)
					(end -0.899187 -1.279127)
					(width 0.2)
				)
				(gr_arc
					(start 1.270645 0.990112)
					(mid -0.228522 0.222449)
					(end -0.991463 -1.279127)
					(width 0.2)
				)
				(gr_arc
					(start 1.266278 1.081674)
					(mid -0.294507 0.285313)
					(end -1.083663 -1.279127)
					(width 0.2)
				)
				(gr_line
					(start 1.279127 0.250195)
					(end 1.279127 1.083663)
					(width 0.2)
				)
				(gr_line
					(start -0.250195 -1.279127)
					(end -1.083663 -1.279127)
					(width 0.2)
				)
			)
		)
		(pad "" smd custom
			(at 1.7 1.7 90)
			(size 0.62 0.62)
			(layers "B.Paste")
			(thermal_bridge_angle 90)
			(options
				(clearance outline)
				(anchor circle)
			)
			(primitives
				(gr_arc
					(start 1.266786 0.24747)
					(mid 0.285453 -0.29439)
					(end -0.250195 -1.279127)
					(width 0.2)
				)
				(gr_arc
					(start 1.259603 0.339191)
					(mid 0.218448 -0.232561)
					(end -0.34334 -1.279127)
					(width 0.2)
				)
				(gr_arc
					(start 1.255279 0.431435)
					(mid 0.152481 -0.169693)
					(end -0.436309 -1.279127)
					(width 0.2)
				)
				(gr_arc
					(start 1.253811 0.524161)
					(mid 0.087542 -0.105784)
					(end -0.529126 -1.279127)
					(width 0.2)
				)
				(gr_arc
					(start 1.275473 0.621136)
					(mid 0.0309 -0.033527)
					(end -0.621807 -1.279127)
					(width 0.2)
				)
				(gr_arc
					(start 1.263664 0.711602)
					(mid -0.037759 0.026651)
					(end -0.71437 -1.279127)
					(width 0.2)
				)
				(gr_arc
					(start 1.253435 0.802342)
					(mid -0.105837 0.087395)
					(end -0.806826 -1.279127)
					(width 0.2)
				)
				(gr_arc
					(start 1.267475 0.897258)
					(mid -0.165236 0.156885)
					(end -0.899187 -1.279127)
					(width 0.2)
				)
				(gr_arc
					(start 1.270645 0.990112)
					(mid -0.228522 0.222449)
					(end -0.991463 -1.279127)
					(width 0.2)
				)
				(gr_arc
					(start 1.266278 1.081674)
					(mid -0.294507 0.285313)
					(end -1.083663 -1.279127)
					(width 0.2)
				)
				(gr_line
					(start 1.279127 0.250195)
					(end 1.279127 1.083663)
					(width 0.2)
				)
				(gr_line
					(start -0.250195 -1.279127)
					(end -1.083663 -1.279127)
					(width 0.2)
				)
			)
		)
		(pad "1" thru_hole circle
			(at 0 0)
			(size 6 6)
			(drill 3.7)
			(layers "*.Cu" "*.Mask")
			(remove_unused_layers no)
			(net 3 "GND")
			(pintype "passive")
		)
	)
	(footprint "antmicro-footprints:C_0402_1005Metric"
		(layer "B.Cu")
		(at 119.067962 115.7665 -90)
		(descr "Capacitor SMD 0402")
		(tags "capacitor SMD 0402")
		(property "Reference" "C506"
			(at 1.33 1.88 90)
			(layer "B.SilkS")
			(effects
				(font
					(size 0.7 0.7)
					(thickness 0.15)
				)
				(justify left bottom mirror)
			)
		)
		(property "Value" "C_1u_0402"
			(at -1.022927 -2.155213 90)
			(layer "B.Fab")
			(effects
				(font
					(size 0.7 0.7)
					(thickness 0.15)
				)
				(justify left bottom mirror)
			)
		)
		(property "Datasheet" "https://product.tdk.com/en/search/capacitor/ceramic/mlcc/info?part_no=C1005X6S1A105K050BC"
			(at 0 0 270)
			(layer "B.Fab")
			(hide yes)
			(effects
				(font
					(size 1.27 1.27)
					(thickness 0.15)
				)
			)
		)
		(property "Manufacturer" "TDK"
			(at 0 0 270)
			(unlocked yes)
			(layer "B.Fab")
			(hide yes)
			(effects
				(font
					(size 1 1)
					(thickness 0.15)
				)
				(justify mirror)
			)
		)
		(property "MPN" "C1005X6S1A105K050BC"
			(at 0 0 270)
			(unlocked yes)
			(layer "B.Fab")
			(hide yes)
			(effects
				(font
					(size 1 1)
					(thickness 0.15)
				)
				(justify mirror)
			)
		)
		(property "Val" "1u"
			(at 0 0 270)
			(unlocked yes)
			(layer "B.Fab")
			(hide yes)
			(effects
				(font
					(size 1 1)
					(thickness 0.15)
				)
				(justify mirror)
			)
		)
		(property "License" "Apache-2.0"
			(at 0 0 270)
			(unlocked yes)
			(layer "B.Fab")
			(hide yes)
			(effects
				(font
					(size 1 1)
					(thickness 0.15)
				)
				(justify mirror)
			)
		)
		(property "Author" "Antmicro"
			(at 0 0 270)
			(unlocked yes)
			(layer "B.Fab")
			(hide yes)
			(effects
				(font
					(size 1 1)
					(thickness 0.15)
				)
				(justify mirror)
			)
		)
		(property "Voltage" ""
			(at 0 0 270)
			(unlocked yes)
			(layer "B.Fab")
			(hide yes)
			(effects
				(font
					(size 1 1)
					(thickness 0.15)
				)
				(justify mirror)
			)
		)
		(property "Dielectric" ""
			(at 0 0 270)
			(unlocked yes)
			(layer "B.Fab")
			(hide yes)
			(effects
				(font
					(size 1 1)
					(thickness 0.15)
				)
				(justify mirror)
			)
		)
		(sheetname "/NVMe & microSD/")
		(sheetfile "nvme-micro-sd.kicad_sch")
		(attr smd)
		(fp_rect
			(start -0.925 0.47)
			(end 0.925 -0.47)
			(stroke
				(width 0.05)
				(type default)
			)
			(fill no)
			(layer "B.CrtYd")
		)
		(fp_line
			(start -0.494 0.25)
			(end 0.504 0.25)
			(stroke
				(width 0.15)
				(type solid)
			)
			(layer "B.Fab")
		)
		(fp_line
			(start 0.504 0.25)
			(end 0.504 -0.248)
			(stroke
				(width 0.15)
				(type solid)
			)
			(layer "B.Fab")
		)
		(fp_line
			(start -0.494 -0.248)
			(end -0.494 0.25)
			(stroke
				(width 0.15)
				(type solid)
			)
			(layer "B.Fab")
		)
		(fp_line
			(start 0.504 -0.248)
			(end -0.494 -0.248)
			(stroke
				(width 0.15)
				(type solid)
			)
			(layer "B.Fab")
		)
		(fp_text user "Author: Antmicro"
			(at -0.939 -3.399 90)
			(layer "B.Fab")
			(effects
				(font
					(size 0.7 0.7)
					(thickness 0.15)
				)
				(justify left bottom mirror)
			)
		)
		(fp_text user "License: Apache-2.0"
			(at -0.939 -5.799 90)
			(layer "B.Fab")
			(effects
				(font
					(size 0.7 0.7)
					(thickness 0.15)
				)
				(justify left bottom mirror)
			)
		)
		(fp_text user "${REFERENCE}"
			(at -0.939 -4.599 90)
			(layer "B.Fab")
			(effects
				(font
					(size 0.7 0.7)
					(thickness 0.15)
				)
				(justify left bottom mirror)
			)
		)
		(pad "1" smd roundrect
			(at -0.48 0 270)
			(size 0.59 0.64)
			(layers "B.Cu" "B.Mask" "B.Paste")
			(roundrect_rratio 0.25)
			(net 3 "GND")
			(pintype "passive")
		)
		(pad "2" smd roundrect
			(at 0.48 0 270)
			(size 0.59 0.64)
			(layers "B.Cu" "B.Mask" "B.Paste")
			(roundrect_rratio 0.25)
			(net 65 "3V3_SSD")
			(pintype "passive")
		)
	)
	(footprint "antmicro-footprints:TP_SMD_0.75mm"
		(layer "B.Cu")
		(at 80.55 147.9)
		(property "Reference" "TP204"
			(at 0.375 1.105 0)
			(layer "B.SilkS")
			(effects
				(font
					(size 0.7 0.7)
					(thickness 0.15)
				)
				(justify right bottom mirror)
			)
		)
		(property "Value" "TP_0.75mm_SMD"
			(at 0 -1.2 0)
			(layer "B.Fab")
			(effects
				(font
					(size 0.7 0.7)
					(thickness 0.15)
				)
				(justify right bottom mirror)
			)
		)
		(property "Author" "Antmicro"
			(at 0 0 0)
			(unlocked yes)
			(layer "B.Fab")
			(hide yes)
			(effects
				(font
					(size 1 1)
					(thickness 0.15)
				)
				(justify mirror)
			)
		)
		(property "License" "Apache-2.0"
			(at 0 0 0)
			(unlocked yes)
			(layer "B.Fab")
			(hide yes)
			(effects
				(font
					(size 1 1)
					(thickness 0.15)
				)
				(justify mirror)
			)
		)
		(property "MPN" ""
			(at 0 0 0)
			(unlocked yes)
			(layer "B.Fab")
			(hide yes)
			(effects
				(font
					(size 1 1)
					(thickness 0.15)
				)
				(justify mirror)
			)
		)
		(property "Manufacturer" ""
			(at 0 0 0)
			(unlocked yes)
			(layer "B.Fab")
			(hide yes)
			(effects
				(font
					(size 1 1)
					(thickness 0.15)
				)
				(justify mirror)
			)
		)
		(sheetname "/Compute module/")
		(sheetfile "compute-module.kicad_sch")
		(attr exclude_from_pos_files exclude_from_bom)
		(fp_circle
			(center 0 0)
			(end 0.475 0)
			(stroke
				(width 0.05)
				(type default)
			)
			(fill no)
			(layer "B.CrtYd")
		)
		(fp_text user "Author: Antmicro"
			(at -0.4 -3.901 180)
			(layer "B.Fab")
			(effects
				(font
					(size 0.7 0.7)
					(thickness 0.15)
				)
				(justify left bottom mirror)
			)
		)
		(fp_text user "License: Apache-2.0"
			(at -0.4 -5.101 180)
			(layer "B.Fab")
			(effects
				(font
					(size 0.7 0.7)
					(thickness 0.15)
				)
				(justify left bottom mirror)
			)
		)
		(fp_text user "${REFERENCE}"
			(at -0.4 -2.7 180)
			(layer "B.Fab")
			(effects
				(font
					(size 0.7 0.7)
					(thickness 0.15)
				)
				(justify left bottom mirror)
			)
		)
		(pad "1" smd circle
			(at 0 0)
			(size 0.75 0.75)
			(layers "B.Cu" "B.Mask")
			(net 215 "/Compute module/SYNC_OUT")
			(pinfunction "1")
			(pintype "passive")
		)
	)
	(footprint "antmicro-footprints:R_0402_1005Metric"
		(layer "B.Cu")
		(at 41.857962 159.5865 180)
		(descr "Resistor SMD 0402")
		(tags "resistor SMD 0402")
		(property "Reference" "R307"
			(at 0.82 -1.07 0)
			(layer "B.SilkS")
			(effects
				(font
					(size 0.7 0.7)
					(thickness 0.15)
				)
				(justify left bottom mirror)
			)
		)
		(property "Value" "R_4k7_0402"
			(at -1.011843 -1.772047 0)
			(layer "B.Fab")
			(effects
				(font
					(size 0.7 0.7)
					(thickness 0.15)
				)
				(justify left bottom mirror)
			)
		)
		(property "Datasheet" "https://www.bourns.com/docs/product-datasheets/cr.pdf"
			(at 0 0 180)
			(layer "B.Fab")
			(hide yes)
			(effects
				(font
					(size 1.27 1.27)
					(thickness 0.15)
				)
			)
		)
		(property "Manufacturer" "Bourns"
			(at 0 0 180)
			(unlocked yes)
			(layer "B.Fab")
			(hide yes)
			(effects
				(font
					(size 1 1)
					(thickness 0.15)
				)
				(justify mirror)
			)
		)
		(property "MPN" "CR0402-FX-4701GLF"
			(at 0 0 180)
			(unlocked yes)
			(layer "B.Fab")
			(hide yes)
			(effects
				(font
					(size 1 1)
					(thickness 0.15)
				)
				(justify mirror)
			)
		)
		(property "Val" "4k7"
			(at 0 0 180)
			(unlocked yes)
			(layer "B.Fab")
			(hide yes)
			(effects
				(font
					(size 1 1)
					(thickness 0.15)
				)
				(justify mirror)
			)
		)
		(property "License" "Apache-2.0"
			(at 0 0 180)
			(unlocked yes)
			(layer "B.Fab")
			(hide yes)
			(effects
				(font
					(size 1 1)
					(thickness 0.15)
				)
				(justify mirror)
			)
		)
		(property "Author" "Antmicro"
			(at 0 0 180)
			(unlocked yes)
			(layer "B.Fab")
			(hide yes)
			(effects
				(font
					(size 1 1)
					(thickness 0.15)
				)
				(justify mirror)
			)
		)
		(property "Tolerance" "1%"
			(at 0 0 180)
			(unlocked yes)
			(layer "B.Fab")
			(hide yes)
			(effects
				(font
					(size 1 1)
					(thickness 0.15)
				)
				(justify mirror)
			)
		)
		(sheetname "/Supply/")
		(sheetfile "supply.kicad_sch")
		(attr smd)
		(fp_rect
			(start -0.925 0.47)
			(end 0.925 -0.47)
			(stroke
				(width 0.05)
				(type default)
			)
			(fill no)
			(layer "B.CrtYd")
		)
		(fp_rect
			(start -0.5 0.25)
			(end 0.5 -0.25)
			(stroke
				(width 0.15)
				(type solid)
			)
			(fill no)
			(layer "B.Fab")
		)
		(fp_text user "Author: Antmicro"
			(at -0.95 -4.169 0)
			(layer "B.Fab")
			(effects
				(font
					(size 0.7 0.7)
					(thickness 0.15)
				)
				(justify left bottom mirror)
			)
		)
		(fp_text user "License: Apache-2.0"
			(at -0.95 -5.169 0)
			(layer "B.Fab")
			(effects
				(font
					(size 0.7 0.7)
					(thickness 0.15)
				)
				(justify left bottom mirror)
			)
		)
		(fp_text user "${REFERENCE}"
			(at -0.95 -3.168 0)
			(layer "B.Fab")
			(effects
				(font
					(size 0.7 0.7)
					(thickness 0.15)
				)
				(justify left bottom mirror)
			)
		)
		(pad "1" smd roundrect
			(at -0.48 0 180)
			(size 0.59 0.64)
			(layers "B.Cu" "B.Mask" "B.Paste")
			(roundrect_rratio 0.25)
			(net 17 "Net-(Q307-G)")
			(pintype "passive")
		)
		(pad "2" smd roundrect
			(at 0.48 0 180)
			(size 0.59 0.64)
			(layers "B.Cu" "B.Mask" "B.Paste")
			(roundrect_rratio 0.25)
			(net 21 "/Supply/VCC_IN")
			(pintype "passive")
		)
	)
)
